(kicad_pcb
	(version 20260206)
	(generator "pcbnew")
	(generator_version "10.0")
	(general
		(thickness 1.6)
		(legacy_teardrops no)
	)
	(paper "A4")
	(title_block
		(title "v1-chassis-manager — T6M_CM_d_v01_1031_1645.brd")
		(comment 1 "Open CloudServer (Microsoft) / footprints 1875-1884 of 2512")
	)
	(layers
		(0 "F.Cu" signal "TOP")
		(4 "In1.Cu" signal "GND1")
		(6 "In2.Cu" signal "IN1")
		(8 "In3.Cu" signal "VCC1")
		(10 "In4.Cu" signal "VCC2")
		(12 "In5.Cu" signal "GND2")
		(14 "In6.Cu" signal "IN2")
		(16 "In7.Cu" signal "IN3")
		(18 "In8.Cu" signal "GND3")
		(2 "B.Cu" signal "BOTTOM")
		(9 "F.Adhes" user "F.Adhesive")
		(11 "B.Adhes" user "B.Adhesive")
		(13 "F.Paste" user "Package Geometry/Pastemask Top")
		(15 "B.Paste" user "Package Geometry/Pastemask Bottom")
		(5 "F.SilkS" user "Ref Des/Silkscreen Top")
		(7 "B.SilkS" user "Ref Des/Silkscreen Bottom")
		(1 "F.Mask" user "Board Geometry/Soldermask Top")
		(3 "B.Mask" user "Board Geometry/Soldermask Bottom")
		(17 "Dwgs.User" user "User.Drawings")
		(19 "Cmts.User" user "User.Comments")
		(21 "Eco1.User" user "User.Eco1")
		(23 "Eco2.User" user "User.Eco2")
		(25 "Edge.Cuts" user "Board Geometry/Outline")
		(27 "Margin" user)
		(31 "F.CrtYd" user "Package Geometry/Place Bound Top")
		(29 "B.CrtYd" user "Package Geometry/Place Bound Bottom")
		(35 "F.Fab" user "Ref Des/Assembly Top")
		(33 "B.Fab" user "Ref Des/Assembly Bottom")
	)
	(footprint ""
		(layer "B.Cu")
		(at 90.81262 -178.086512)
		(property "Reference" "R697"
			(at 24.902414 20.083272 0)
			(unlocked yes)
			(layer "B.SilkS")
			(effects
				(font
					(size 0.7874 0.5842)
					(thickness 0.1524)
				)
				(justify left mirror)
			)
		)
		(property "Value" ""
			(at 0 0 0)
			(layer "B.Fab")
			(effects
				(font
					(size 1.27 1.27)
				)
				(justify mirror)
			)
		)
		(duplicate_pad_numbers_are_jumpers no)
		(fp_line
			(start -0.7874 -0.4064)
			(end -0.7874 0.4064)
			(stroke
				(width 0.1524)
				(type default)
			)
			(layer "B.SilkS")
		)
		(fp_line
			(start -0.7874 0.4064)
			(end 0.7874 0.4064)
			(stroke
				(width 0.1524)
				(type default)
			)
			(layer "B.SilkS")
		)
		(fp_line
			(start 0.7874 -0.4064)
			(end -0.7874 -0.4064)
			(stroke
				(width 0.1524)
				(type default)
			)
			(layer "B.SilkS")
		)
		(fp_line
			(start 0.7874 0.4064)
			(end 0.7874 -0.4064)
			(stroke
				(width 0.1524)
				(type default)
			)
			(layer "B.SilkS")
		)
		(fp_poly
			(pts
				(xy 0.508 0.2794) (xy 0.508 0.2286) (xy 0.635 0.2286) (xy 0.635 -0.254) (xy 0.5334 -0.254) (xy 0.5334 -0.2794)
				(xy -0.5334 -0.2794) (xy -0.5334 -0.254) (xy -0.635 -0.254) (xy -0.635 0.254) (xy -0.5334 0.254)
				(xy -0.5334 0.2794)
			)
			(stroke
				(width 0)
				(type default)
			)
			(fill no)
			(layer "B.CrtYd")
		)
		(pad "1" smd rect
			(at -0.40005 0 180)
			(size 0.4572 0.508)
			(layers "B.Cu" "B.Mask" "B.Paste")
			(net "T3_NODE1_EN")
		)
		(pad "2" smd rect
			(at 0.40005 0 180)
			(size 0.4572 0.508)
			(layers "B.Cu" "B.Mask" "B.Paste")
			(net "P5V_NODE1")
		)
	)
	(footprint ""
		(layer "B.Cu")
		(at 135.84047 -105.186734 90)
		(property "Reference" "L2"
			(at -1.768094 -1.67005 270)
			(unlocked yes)
			(layer "B.SilkS")
			(effects
				(font
					(size 0.7874 0.5842)
					(thickness 0.1524)
				)
				(justify left mirror)
			)
		)
		(property "Value" ""
			(at 0 0 90)
			(layer "B.Fab")
			(effects
				(font
					(size 1.27 1.27)
				)
				(justify mirror)
			)
		)
		(duplicate_pad_numbers_are_jumpers no)
		(fp_line
			(start 1.905 -0.8636)
			(end -1.905 -0.8636)
			(stroke
				(width 0.1524)
				(type default)
			)
			(layer "B.SilkS")
		)
		(fp_line
			(start 1.905 0.8382)
			(end 1.905 -0.8382)
			(stroke
				(width 0.1524)
				(type default)
			)
			(layer "B.SilkS")
		)
		(fp_line
			(start 0.127 0.8382)
			(end 0.127 -0.8382)
			(stroke
				(width 0.1524)
				(type default)
			)
			(layer "B.SilkS")
		)
		(fp_line
			(start -0.127 0.8382)
			(end -0.127 -0.8382)
			(stroke
				(width 0.1524)
				(type default)
			)
			(layer "B.SilkS")
		)
		(fp_line
			(start -1.905 0.8382)
			(end -1.905 -0.8382)
			(stroke
				(width 0.1524)
				(type default)
			)
			(layer "B.SilkS")
		)
		(fp_line
			(start -1.905 0.8636)
			(end 1.905 0.8636)
			(stroke
				(width 0.1524)
				(type default)
			)
			(layer "B.SilkS")
		)
		(fp_rect
			(start 1.524 0.7112)
			(end -1.524 -0.7366)
			(stroke
				(width 0)
				(type default)
			)
			(fill no)
			(layer "B.CrtYd")
		)
		(pad "1" smd rect
			(at -0.94996 0 270)
			(size 1.1176 1.3716)
			(layers "B.Cu" "B.Mask" "B.Paste")
			(net "P3V3_CLK_NODE1_R")
		)
		(pad "2" smd rect
			(at 0.94996 0 270)
			(size 1.1176 1.3716)
			(layers "B.Cu" "B.Mask" "B.Paste")
			(net "P3V3_CLK_NODE1")
		)
	)
	(footprint ""
		(layer "B.Cu")
		(at 108.44276 -188.126624 -90)
		(property "Reference" "C739"
			(at -4.080256 -0.63246 270)
			(unlocked yes)
			(layer "B.SilkS")
			(effects
				(font
					(size 0.7874 0.5842)
					(thickness 0.1524)
				)
				(justify left mirror)
			)
		)
		(property "Value" ""
			(at 0 0 90)
			(layer "B.Fab")
			(effects
				(font
					(size 1.27 1.27)
				)
				(justify mirror)
			)
		)
		(duplicate_pad_numbers_are_jumpers no)
		(fp_line
			(start -0.7874 0.4064)
			(end 0.7874 0.4064)
			(stroke
				(width 0.1524)
				(type default)
			)
			(layer "B.SilkS")
		)
		(fp_line
			(start 0.7874 0.4064)
			(end 0.7874 -0.4064)
			(stroke
				(width 0.1524)
				(type default)
			)
			(layer "B.SilkS")
		)
		(fp_line
			(start 0 0.381)
			(end 0 -0.381)
			(stroke
				(width 0.1524)
				(type default)
			)
			(layer "B.SilkS")
		)
		(fp_line
			(start -0.7874 -0.4064)
			(end -0.7874 0.4064)
			(stroke
				(width 0.1524)
				(type default)
			)
			(layer "B.SilkS")
		)
		(fp_line
			(start 0.7874 -0.4064)
			(end -0.7874 -0.4064)
			(stroke
				(width 0.1524)
				(type default)
			)
			(layer "B.SilkS")
		)
		(fp_poly
			(pts
				(xy 0.5334 0.254) (xy 0.635 0.254) (xy 0.635 0.2286) (xy 0.635 -0.254) (xy 0.5334 -0.254) (xy 0.5334 -0.2794)
				(xy -0.5334 -0.2794) (xy -0.5334 -0.254) (xy -0.635 -0.254) (xy -0.635 0.254) (xy -0.5334 0.254)
				(xy -0.5334 0.2794) (xy 0.508 0.2794) (xy 0.5334 0.2794)
			)
			(stroke
				(width 0)
				(type default)
			)
			(fill no)
			(layer "B.CrtYd")
		)
		(pad "1" smd rect
			(at -0.40005 0 90)
			(size 0.4572 0.508)
			(layers "B.Cu" "B.Mask" "B.Paste")
			(net "UART_T7_NODE4_TXD_R")
		)
		(pad "2" smd rect
			(at 0.40005 0 90)
			(size 0.4572 0.508)
			(layers "B.Cu" "B.Mask" "B.Paste")
			(net "GND")
		)
	)
	(footprint ""
		(layer "B.Cu")
		(at 45.642022 -184.922668 -90)
		(property "Reference" "R835"
			(at -4.434586 -0.062738 270)
			(unlocked yes)
			(layer "B.SilkS")
			(effects
				(font
					(size 0.7874 0.5842)
					(thickness 0.1524)
				)
				(justify left mirror)
			)
		)
		(property "Value" ""
			(at 0 0 90)
			(layer "B.Fab")
			(effects
				(font
					(size 1.27 1.27)
				)
				(justify mirror)
			)
		)
		(duplicate_pad_numbers_are_jumpers no)
		(fp_line
			(start -0.7874 0.4064)
			(end 0.7874 0.4064)
			(stroke
				(width 0.1524)
				(type default)
			)
			(layer "B.SilkS")
		)
		(fp_line
			(start 0.7874 0.4064)
			(end 0.7874 -0.4064)
			(stroke
				(width 0.1524)
				(type default)
			)
			(layer "B.SilkS")
		)
		(fp_line
			(start -0.7874 -0.4064)
			(end -0.7874 0.4064)
			(stroke
				(width 0.1524)
				(type default)
			)
			(layer "B.SilkS")
		)
		(fp_line
			(start 0.7874 -0.4064)
			(end -0.7874 -0.4064)
			(stroke
				(width 0.1524)
				(type default)
			)
			(layer "B.SilkS")
		)
		(fp_poly
			(pts
				(xy 0.508 0.2794) (xy 0.508 0.2286) (xy 0.635 0.2286) (xy 0.635 -0.254) (xy 0.5334 -0.254) (xy 0.5334 -0.2794)
				(xy -0.5334 -0.2794) (xy -0.5334 -0.254) (xy -0.635 -0.254) (xy -0.635 0.254) (xy -0.5334 0.254)
				(xy -0.5334 0.2794)
			)
			(stroke
				(width 0)
				(type default)
			)
			(fill no)
			(layer "B.CrtYd")
		)
		(pad "1" smd rect
			(at -0.40005 0 90)
			(size 0.4572 0.508)
			(layers "B.Cu" "B.Mask" "B.Paste")
			(net "MATE_R_N")
		)
		(pad "2" smd rect
			(at 0.40005 0 90)
			(size 0.4572 0.508)
			(layers "B.Cu" "B.Mask" "B.Paste")
			(net "MATE_N")
		)
	)
	(footprint ""
		(layer "B.Cu")
		(at 85.692742 -29.793438 180)
		(property "Reference" "R208"
			(at -2.110994 -1.18237 0)
			(unlocked yes)
			(layer "B.SilkS")
			(effects
				(font
					(size 0.7874 0.5842)
					(thickness 0.1524)
				)
				(justify left mirror)
			)
		)
		(property "Value" ""
			(at 0 0 0)
			(layer "B.Fab")
			(effects
				(font
					(size 1.27 1.27)
				)
				(justify mirror)
			)
		)
		(duplicate_pad_numbers_are_jumpers no)
		(fp_line
			(start 0.7874 0.4064)
			(end 0.7874 -0.4064)
			(stroke
				(width 0.1524)
				(type default)
			)
			(layer "B.SilkS")
		)
		(fp_line
			(start 0.7874 -0.4064)
			(end -0.7874 -0.4064)
			(stroke
				(width 0.1524)
				(type default)
			)
			(layer "B.SilkS")
		)
		(fp_line
			(start -0.7874 0.4064)
			(end 0.7874 0.4064)
			(stroke
				(width 0.1524)
				(type default)
			)
			(layer "B.SilkS")
		)
		(fp_line
			(start -0.7874 -0.4064)
			(end -0.7874 0.4064)
			(stroke
				(width 0.1524)
				(type default)
			)
			(layer "B.SilkS")
		)
		(fp_poly
			(pts
				(xy 0.508 0.2794) (xy 0.508 0.2286) (xy 0.635 0.2286) (xy 0.635 -0.254) (xy 0.5334 -0.254) (xy 0.5334 -0.2794)
				(xy -0.5334 -0.2794) (xy -0.5334 -0.254) (xy -0.635 -0.254) (xy -0.635 0.254) (xy -0.5334 0.254)
				(xy -0.5334 0.2794)
			)
			(stroke
				(width 0)
				(type default)
			)
			(fill no)
			(layer "B.CrtYd")
		)
		(pad "1" smd rect
			(at -0.40005 0)
			(size 0.4572 0.508)
			(layers "B.Cu" "B.Mask" "B.Paste")
			(net "GND")
		)
		(pad "2" smd rect
			(at 0.40005 0)
			(size 0.4572 0.508)
			(layers "B.Cu" "B.Mask" "B.Paste")
			(net "PD_NODE1_DM4")
		)
	)
	(footprint ""
		(layer "B.Cu")
		(at 64.731392 -137.893806 180)
		(property "Reference" "C251"
			(at 38.960806 -54.881018 0)
			(unlocked yes)
			(layer "B.SilkS")
			(effects
				(font
					(size 0.7874 0.5842)
					(thickness 0.1524)
				)
				(justify left mirror)
			)
		)
		(property "Value" ""
			(at 0 0 0)
			(layer "B.Fab")
			(effects
				(font
					(size 1.27 1.27)
				)
				(justify mirror)
			)
		)
		(duplicate_pad_numbers_are_jumpers no)
		(fp_line
			(start 0.7874 0.4064)
			(end 0.7874 -0.4064)
			(stroke
				(width 0.1524)
				(type default)
			)
			(layer "B.SilkS")
		)
		(fp_line
			(start 0.7874 -0.4064)
			(end -0.7874 -0.4064)
			(stroke
				(width 0.1524)
				(type default)
			)
			(layer "B.SilkS")
		)
		(fp_line
			(start 0 0.381)
			(end 0 -0.381)
			(stroke
				(width 0.1524)
				(type default)
			)
			(layer "B.SilkS")
		)
		(fp_line
			(start -0.7874 0.4064)
			(end 0.7874 0.4064)
			(stroke
				(width 0.1524)
				(type default)
			)
			(layer "B.SilkS")
		)
		(fp_line
			(start -0.7874 -0.4064)
			(end -0.7874 0.4064)
			(stroke
				(width 0.1524)
				(type default)
			)
			(layer "B.SilkS")
		)
		(fp_poly
			(pts
				(xy 0.5334 0.254) (xy 0.635 0.254) (xy 0.635 0.2286) (xy 0.635 -0.254) (xy 0.5334 -0.254) (xy 0.5334 -0.2794)
				(xy -0.5334 -0.2794) (xy -0.5334 -0.254) (xy -0.635 -0.254) (xy -0.635 0.254) (xy -0.5334 0.254)
				(xy -0.5334 0.2794) (xy 0.508 0.2794) (xy 0.5334 0.2794)
			)
			(stroke
				(width 0)
				(type default)
			)
			(fill no)
			(layer "B.CrtYd")
		)
		(pad "1" smd rect
			(at -0.40005 0)
			(size 0.4572 0.508)
			(layers "B.Cu" "B.Mask" "B.Paste")
			(net "P3V3_NODE1")
		)
		(pad "2" smd rect
			(at 0.40005 0)
			(size 0.4572 0.508)
			(layers "B.Cu" "B.Mask" "B.Paste")
			(net "GND")
		)
	)
	(footprint ""
		(layer "B.Cu")
		(at 59.45124 -70.133718 -90)
		(property "Reference" "L5"
			(at 32.046926 10.44067 270)
			(unlocked yes)
			(layer "B.SilkS")
			(effects
				(font
					(size 0.7874 0.5842)
					(thickness 0.1524)
				)
				(justify left mirror)
			)
		)
		(property "Value" ""
			(at 0 0 90)
			(layer "B.Fab")
			(effects
				(font
					(size 1.27 1.27)
				)
				(justify mirror)
			)
		)
		(duplicate_pad_numbers_are_jumpers no)
		(fp_line
			(start -0.7874 0.4064)
			(end 0.7874 0.4064)
			(stroke
				(width 0.1524)
				(type default)
			)
			(layer "B.SilkS")
		)
		(fp_line
			(start -0.0889 0.4064)
			(end -0.0889 -0.4064)
			(stroke
				(width 0.1524)
				(type default)
			)
			(layer "B.SilkS")
		)
		(fp_line
			(start 0.0889 0.4064)
			(end 0.0889 -0.4064)
			(stroke
				(width 0.1524)
				(type default)
			)
			(layer "B.SilkS")
		)
		(fp_line
			(start 0.7874 0.4064)
			(end 0.7874 -0.4064)
			(stroke
				(width 0.1524)
				(type default)
			)
			(layer "B.SilkS")
		)
		(fp_line
			(start -0.7874 -0.4064)
			(end -0.7874 0.4064)
			(stroke
				(width 0.1524)
				(type default)
			)
			(layer "B.SilkS")
		)
		(fp_line
			(start 0.7874 -0.4064)
			(end -0.7874 -0.4064)
			(stroke
				(width 0.1524)
				(type default)
			)
			(layer "B.SilkS")
		)
		(fp_poly
			(pts
				(xy 0.5334 0.254) (xy 0.635 0.254) (xy 0.635 0.2286) (xy 0.635 -0.254) (xy 0.5334 -0.254) (xy 0.5334 -0.2794)
				(xy -0.5334 -0.2794) (xy -0.5334 -0.254) (xy -0.635 -0.254) (xy -0.635 0.254) (xy -0.5334 0.254)
				(xy -0.5334 0.2794) (xy 0.508 0.2794) (xy 0.5334 0.2794)
			)
			(stroke
				(width 0)
				(type default)
			)
			(fill no)
			(layer "B.CrtYd")
		)
		(pad "1" smd rect
			(at -0.40005 0 90)
			(size 0.4572 0.508)
			(layers "B.Cu" "B.Mask" "B.Paste")
			(net "P1V05_NODE1")
		)
		(pad "2" smd rect
			(at 0.40005 0 90)
			(size 0.4572 0.508)
			(layers "B.Cu" "B.Mask" "B.Paste")
			(net "P1V05_VCCPLL_DDR3_NODE1")
		)
	)
	(footprint ""
		(layer "B.Cu")
		(at 138.79576 -187.872624 -90)
		(property "Reference" "C627"
			(at -4.565396 1.448308 270)
			(unlocked yes)
			(layer "B.SilkS")
			(effects
				(font
					(size 0.7874 0.5842)
					(thickness 0.1524)
				)
				(justify left mirror)
			)
		)
		(property "Value" ""
			(at 0 0 90)
			(layer "B.Fab")
			(effects
				(font
					(size 1.27 1.27)
				)
				(justify mirror)
			)
		)
		(duplicate_pad_numbers_are_jumpers no)
		(fp_line
			(start -0.7874 0.4064)
			(end 0.7874 0.4064)
			(stroke
				(width 0.1524)
				(type default)
			)
			(layer "B.SilkS")
		)
		(fp_line
			(start 0.7874 0.4064)
			(end 0.7874 -0.4064)
			(stroke
				(width 0.1524)
				(type default)
			)
			(layer "B.SilkS")
		)
		(fp_line
			(start 0 0.381)
			(end 0 -0.381)
			(stroke
				(width 0.1524)
				(type default)
			)
			(layer "B.SilkS")
		)
		(fp_line
			(start -0.7874 -0.4064)
			(end -0.7874 0.4064)
			(stroke
				(width 0.1524)
				(type default)
			)
			(layer "B.SilkS")
		)
		(fp_line
			(start 0.7874 -0.4064)
			(end -0.7874 -0.4064)
			(stroke
				(width 0.1524)
				(type default)
			)
			(layer "B.SilkS")
		)
		(fp_poly
			(pts
				(xy 0.5334 0.254) (xy 0.635 0.254) (xy 0.635 0.2286) (xy 0.635 -0.254) (xy 0.5334 -0.254) (xy 0.5334 -0.2794)
				(xy -0.5334 -0.2794) (xy -0.5334 -0.254) (xy -0.635 -0.254) (xy -0.635 0.254) (xy -0.5334 0.254)
				(xy -0.5334 0.2794) (xy 0.508 0.2794) (xy 0.5334 0.2794)
			)
			(stroke
				(width 0)
				(type default)
			)
			(fill no)
			(layer "B.CrtYd")
		)
		(pad "1" smd rect
			(at -0.40005 0 90)
			(size 0.4572 0.508)
			(layers "B.Cu" "B.Mask" "B.Paste")
			(net "T9_NODE2_EN_R")
		)
		(pad "2" smd rect
			(at 0.40005 0 90)
			(size 0.4572 0.508)
			(layers "B.Cu" "B.Mask" "B.Paste")
			(net "GND")
		)
	)
	(footprint ""
		(layer "B.Cu")
		(at 58.019188 -56.108854)
		(property "Reference" "R32"
			(at 3.14579 0.043688 0)
			(unlocked yes)
			(layer "B.SilkS")
			(effects
				(font
					(size 0.7874 0.5842)
					(thickness 0.1524)
				)
				(justify left mirror)
			)
		)
		(property "Value" ""
			(at 0 0 0)
			(layer "B.Fab")
			(effects
				(font
					(size 1.27 1.27)
				)
				(justify mirror)
			)
		)
		(duplicate_pad_numbers_are_jumpers no)
		(fp_line
			(start -0.7874 -0.4064)
			(end -0.7874 0.4064)
			(stroke
				(width 0.1524)
				(type default)
			)
			(layer "B.SilkS")
		)
		(fp_line
			(start -0.7874 0.4064)
			(end 0.7874 0.4064)
			(stroke
				(width 0.1524)
				(type default)
			)
			(layer "B.SilkS")
		)
		(fp_line
			(start 0.7874 -0.4064)
			(end -0.7874 -0.4064)
			(stroke
				(width 0.1524)
				(type default)
			)
			(layer "B.SilkS")
		)
		(fp_line
			(start 0.7874 0.4064)
			(end 0.7874 -0.4064)
			(stroke
				(width 0.1524)
				(type default)
			)
			(layer "B.SilkS")
		)
		(fp_poly
			(pts
				(xy 0.508 0.2794) (xy 0.508 0.2286) (xy 0.635 0.2286) (xy 0.635 -0.254) (xy 0.5334 -0.254) (xy 0.5334 -0.2794)
				(xy -0.5334 -0.2794) (xy -0.5334 -0.254) (xy -0.635 -0.254) (xy -0.635 0.254) (xy -0.5334 0.254)
				(xy -0.5334 0.2794)
			)
			(stroke
				(width 0)
				(type default)
			)
			(fill no)
			(layer "B.CrtYd")
		)
		(pad "1" smd rect
			(at -0.40005 0 180)
			(size 0.4572 0.508)
			(layers "B.Cu" "B.Mask" "B.Paste")
			(net "M_DDR3_NODE1_MON1P")
		)
		(pad "2" smd rect
			(at 0.40005 0 180)
			(size 0.4572 0.508)
			(layers "B.Cu" "B.Mask" "B.Paste")
			(net "M_DDR3_NODE1_MON1N")
		)
	)
	(footprint ""
		(layer "B.Cu")
		(at 137.550652 -135.84555 90)
		(property "Reference" "C879"
			(at -5.04825 -0.15875 270)
			(unlocked yes)
			(layer "B.SilkS")
			(effects
				(font
					(size 0.7874 0.5842)
					(thickness 0.1524)
				)
				(justify left mirror)
			)
		)
		(property "Value" ""
			(at 0 0 90)
			(layer "B.Fab")
			(effects
				(font
					(size 1.27 1.27)
				)
				(justify mirror)
			)
		)
		(duplicate_pad_numbers_are_jumpers no)
		(fp_line
			(start 0.7874 -0.4064)
			(end -0.7874 -0.4064)
			(stroke
				(width 0.1524)
				(type default)
			)
			(layer "B.SilkS")
		)
		(fp_line
			(start -0.7874 -0.4064)
			(end -0.7874 0.4064)
			(stroke
				(width 0.1524)
				(type default)
			)
			(layer "B.SilkS")
		)
		(fp_line
			(start 0 0.381)
			(end 0 -0.381)
			(stroke
				(width 0.1524)
				(type default)
			)
			(layer "B.SilkS")
		)
		(fp_line
			(start 0.7874 0.4064)
			(end 0.7874 -0.4064)
			(stroke
				(width 0.1524)
				(type default)
			)
			(layer "B.SilkS")
		)
		(fp_line
			(start -0.7874 0.4064)
			(end 0.7874 0.4064)
			(stroke
				(width 0.1524)
				(type default)
			)
			(layer "B.SilkS")
		)
		(fp_poly
			(pts
				(xy 0.5334 0.254) (xy 0.635 0.254) (xy 0.635 0.2286) (xy 0.635 -0.254) (xy 0.5334 -0.254) (xy 0.5334 -0.2794)
				(xy -0.5334 -0.2794) (xy -0.5334 -0.254) (xy -0.635 -0.254) (xy -0.635 0.254) (xy -0.5334 0.254)
				(xy -0.5334 0.2794) (xy 0.508 0.2794) (xy 0.5334 0.2794)
			)
			(stroke
				(width 0)
				(type default)
			)
			(fill no)
			(layer "B.CrtYd")
		)
		(pad "1" smd rect
			(at -0.40005 0 270)
			(size 0.4572 0.508)
			(layers "B.Cu" "B.Mask" "B.Paste")
			(net "P1V0_NODE1")
		)
		(pad "2" smd rect
			(at 0.40005 0 270)
			(size 0.4572 0.508)
			(layers "B.Cu" "B.Mask" "B.Paste")
			(net "GND")
		)
	)
)
